FILE_TYPE=LIBRARY_PARTS;
primitive 'RS53318LR';
  pin
    'VIN1':
      PIN_NUMBER='(10)';
      PINUSE='POWER';
      NO_LOAD_CHECK='Both';
      NO_IO_CHECK='Both';
      NO_ASSERT_CHECK='TRUE';
      NO_DIR_CHECK='TRUE';
      ALLOW_CONNECT='TRUE';
    'PGOOD':
      PIN_NUMBER='(9)';
      OUTPUT_LOAD='(1.0,-1.0)';
    'PGND':
      PIN_NUMBER='(11_18)';
      PINUSE='POWER';
      NO_LOAD_CHECK='Both';
      NO_IO_CHECK='Both';
      NO_ASSERT_CHECK='TRUE';
      NO_DIR_CHECK='TRUE';
      ALLOW_CONNECT='TRUE';
    'EN':
      PIN_NUMBER='(8)';
      INPUT_LOAD='(-0.01,0.01)';
    'BST':
      PIN_NUMBER='(1)';
      INPUT_LOAD='(-0.01,0.01)';
    'FB':
      PIN_NUMBER='(7)';
      INPUT_LOAD='(-0.01,0.01)';
    'AGND':
      PIN_NUMBER='(2)';
      PINUSE='POWER';
      NO_LOAD_CHECK='Both';
      NO_IO_CHECK='Both';
      NO_ASSERT_CHECK='TRUE';
      NO_DIR_CHECK='TRUE';
      ALLOW_CONNECT='TRUE';
    'VCC':
      PIN_NUMBER='(19)';
      PINUSE='POWER';
      NO_LOAD_CHECK='Both';
      NO_IO_CHECK='Both';
      NO_ASSERT_CHECK='TRUE';
      NO_DIR_CHECK='TRUE';
      ALLOW_CONNECT='TRUE';
    'RTN':
      PIN_NUMBER='(6)';
      PINUSE='POWER';
      NO_LOAD_CHECK='Both';
      NO_IO_CHECK='Both';
      NO_ASSERT_CHECK='TRUE';
      NO_DIR_CHECK='TRUE';
      ALLOW_CONNECT='TRUE';
    'SW':
      PIN_NUMBER='(20)';
      OUTPUT_LOAD='(1.0,-1.0)';
    'REF':
      PIN_NUMBER='(5)';
      INPUT_LOAD='(-0.01,0.01)';
    'MODE':
      PIN_NUMBER='(4)';
      INPUT_LOAD='(-0.01,0.01)';
    'CS':
      PIN_NUMBER='(3)';
      INPUT_LOAD='(-0.01,0.01)';
    'VIN2':
      PIN_NUMBER='(21)';
      PINUSE='POWER';
      NO_LOAD_CHECK='Both';
      NO_IO_CHECK='Both';
      NO_ASSERT_CHECK='TRUE';
      NO_DIR_CHECK='TRUE';
      ALLOW_CONNECT='TRUE';
  end_pin;
  body
    PART_NAME='RS53318LR';
    BODY_NAME='RS53318LR';
    PHYS_DES_PREFIX='U';
    CLASS='IC';
  end_body;
end_primitive;

END.
